(kicad_pcb
	(version 20260206)
	(generator "pcbnew")
	(generator_version "10.0")
	(general
		(thickness 1.6)
		(legacy_teardrops no)
	)
	(paper "A4")
	(title_block
		(title "v1-chassis-manager — T6M_CM_d_v01_1031_1645.brd")
		(comment 1 "Open CloudServer (Microsoft) / footprints 1786-1795 of 2512")
	)
	(layers
		(0 "F.Cu" signal "TOP")
		(4 "In1.Cu" signal "GND1")
		(6 "In2.Cu" signal "IN1")
		(8 "In3.Cu" signal "VCC1")
		(10 "In4.Cu" signal "VCC2")
		(12 "In5.Cu" signal "GND2")
		(14 "In6.Cu" signal "IN2")
		(16 "In7.Cu" signal "IN3")
		(18 "In8.Cu" signal "GND3")
		(2 "B.Cu" signal "BOTTOM")
		(9 "F.Adhes" user "F.Adhesive")
		(11 "B.Adhes" user "B.Adhesive")
		(13 "F.Paste" user "Package Geometry/Pastemask Top")
		(15 "B.Paste" user "Package Geometry/Pastemask Bottom")
		(5 "F.SilkS" user "Ref Des/Silkscreen Top")
		(7 "B.SilkS" user "Ref Des/Silkscreen Bottom")
		(1 "F.Mask" user "Board Geometry/Soldermask Top")
		(3 "B.Mask" user "Board Geometry/Soldermask Bottom")
		(17 "Dwgs.User" user "User.Drawings")
		(19 "Cmts.User" user "User.Comments")
		(21 "Eco1.User" user "User.Eco1")
		(23 "Eco2.User" user "User.Eco2")
		(25 "Edge.Cuts" user "Board Geometry/Outline")
		(27 "Margin" user)
		(31 "F.CrtYd" user "Package Geometry/Place Bound Top")
		(29 "B.CrtYd" user "Package Geometry/Place Bound Bottom")
		(35 "F.Fab" user "Ref Des/Assembly Top")
		(33 "B.Fab" user "Ref Des/Assembly Bottom")
	)
	(footprint ""
		(layer "B.Cu")
		(at 114.701574 -107.855766 180)
		(property "Reference" "PC118"
			(at -5.729732 -0.023368 0)
			(unlocked yes)
			(layer "B.SilkS")
			(effects
				(font
					(size 0.7874 0.5842)
					(thickness 0.1524)
				)
				(justify left mirror)
			)
		)
		(property "Value" ""
			(at 0 0 0)
			(layer "B.Fab")
			(effects
				(font
					(size 1.27 1.27)
				)
				(justify mirror)
			)
		)
		(duplicate_pad_numbers_are_jumpers no)
		(fp_line
			(start 1.905 0.8636)
			(end 1.905 -0.8636)
			(stroke
				(width 0.1524)
				(type default)
			)
			(layer "B.SilkS")
		)
		(fp_line
			(start 1.905 -0.8636)
			(end -1.905 -0.8636)
			(stroke
				(width 0.1524)
				(type default)
			)
			(layer "B.SilkS")
		)
		(fp_line
			(start 0 0.8382)
			(end 0 -0.8382)
			(stroke
				(width 0.1524)
				(type default)
			)
			(layer "B.SilkS")
		)
		(fp_line
			(start -1.905 0.8636)
			(end 1.905 0.8636)
			(stroke
				(width 0.1524)
				(type default)
			)
			(layer "B.SilkS")
		)
		(fp_line
			(start -1.905 -0.8636)
			(end -1.905 0.8636)
			(stroke
				(width 0.1524)
				(type default)
			)
			(layer "B.SilkS")
		)
		(fp_rect
			(start 1.524 0.7366)
			(end -1.524 -0.7366)
			(stroke
				(width 0)
				(type default)
			)
			(fill no)
			(layer "B.CrtYd")
		)
		(pad "1" smd rect
			(at -0.94996 0)
			(size 1.1176 1.3716)
			(layers "B.Cu" "B.Mask" "B.Paste")
			(net "GND")
		)
		(pad "2" smd rect
			(at 0.94996 0)
			(size 1.1176 1.3716)
			(layers "B.Cu" "B.Mask" "B.Paste")
			(net "PV_VCCP_NODE1")
		)
	)
	(footprint ""
		(layer "B.Cu")
		(at 52.81676 -185.205624 -90)
		(property "Reference" "R832"
			(at -4.15163 -0.163068 270)
			(unlocked yes)
			(layer "B.SilkS")
			(effects
				(font
					(size 0.7874 0.5842)
					(thickness 0.1524)
				)
				(justify left mirror)
			)
		)
		(property "Value" ""
			(at 0 0 90)
			(layer "B.Fab")
			(effects
				(font
					(size 1.27 1.27)
				)
				(justify mirror)
			)
		)
		(duplicate_pad_numbers_are_jumpers no)
		(fp_line
			(start -0.7874 0.4064)
			(end 0.7874 0.4064)
			(stroke
				(width 0.1524)
				(type default)
			)
			(layer "B.SilkS")
		)
		(fp_line
			(start 0.7874 0.4064)
			(end 0.7874 -0.4064)
			(stroke
				(width 0.1524)
				(type default)
			)
			(layer "B.SilkS")
		)
		(fp_line
			(start -0.7874 -0.4064)
			(end -0.7874 0.4064)
			(stroke
				(width 0.1524)
				(type default)
			)
			(layer "B.SilkS")
		)
		(fp_line
			(start 0.7874 -0.4064)
			(end -0.7874 -0.4064)
			(stroke
				(width 0.1524)
				(type default)
			)
			(layer "B.SilkS")
		)
		(fp_poly
			(pts
				(xy 0.508 0.2794) (xy 0.508 0.2286) (xy 0.635 0.2286) (xy 0.635 -0.254) (xy 0.5334 -0.254) (xy 0.5334 -0.2794)
				(xy -0.5334 -0.2794) (xy -0.5334 -0.254) (xy -0.635 -0.254) (xy -0.635 0.254) (xy -0.5334 0.254)
				(xy -0.5334 0.2794)
			)
			(stroke
				(width 0)
				(type default)
			)
			(fill no)
			(layer "B.CrtYd")
		)
		(pad "1" smd rect
			(at -0.40005 0 90)
			(size 0.4572 0.508)
			(layers "B.Cu" "B.Mask" "B.Paste")
			(net "PSU1_DC_OK_R")
		)
		(pad "2" smd rect
			(at 0.40005 0 90)
			(size 0.4572 0.508)
			(layers "B.Cu" "B.Mask" "B.Paste")
			(net "PSU1_DC_OK_R_BUF")
		)
	)
	(footprint ""
		(layer "B.Cu")
		(at 49.38776 -185.205624 -90)
		(property "Reference" "R840"
			(at -4.15163 -0.163068 270)
			(unlocked yes)
			(layer "B.SilkS")
			(effects
				(font
					(size 0.7874 0.5842)
					(thickness 0.1524)
				)
				(justify left mirror)
			)
		)
		(property "Value" ""
			(at 0 0 90)
			(layer "B.Fab")
			(effects
				(font
					(size 1.27 1.27)
				)
				(justify mirror)
			)
		)
		(duplicate_pad_numbers_are_jumpers no)
		(fp_line
			(start -0.7874 0.4064)
			(end 0.7874 0.4064)
			(stroke
				(width 0.1524)
				(type default)
			)
			(layer "B.SilkS")
		)
		(fp_line
			(start 0.7874 0.4064)
			(end 0.7874 -0.4064)
			(stroke
				(width 0.1524)
				(type default)
			)
			(layer "B.SilkS")
		)
		(fp_line
			(start -0.7874 -0.4064)
			(end -0.7874 0.4064)
			(stroke
				(width 0.1524)
				(type default)
			)
			(layer "B.SilkS")
		)
		(fp_line
			(start 0.7874 -0.4064)
			(end -0.7874 -0.4064)
			(stroke
				(width 0.1524)
				(type default)
			)
			(layer "B.SilkS")
		)
		(fp_poly
			(pts
				(xy 0.508 0.2794) (xy 0.508 0.2286) (xy 0.635 0.2286) (xy 0.635 -0.254) (xy 0.5334 -0.254) (xy 0.5334 -0.2794)
				(xy -0.5334 -0.2794) (xy -0.5334 -0.254) (xy -0.635 -0.254) (xy -0.635 0.254) (xy -0.5334 0.254)
				(xy -0.5334 0.2794)
			)
			(stroke
				(width 0)
				(type default)
			)
			(fill no)
			(layer "B.CrtYd")
		)
		(pad "1" smd rect
			(at -0.40005 0 90)
			(size 0.4572 0.508)
			(layers "B.Cu" "B.Mask" "B.Paste")
			(net "PSU4_DC_OK_R")
		)
		(pad "2" smd rect
			(at 0.40005 0 90)
			(size 0.4572 0.508)
			(layers "B.Cu" "B.Mask" "B.Paste")
			(net "PSU4_DC_OK_R_BUF")
		)
	)
	(footprint ""
		(layer "B.Cu")
		(at 161.782252 -167.141398 180)
		(property "Reference" "U141"
			(at -0.300228 -2.623058 0)
			(unlocked yes)
			(layer "B.SilkS")
			(effects
				(font
					(size 0.7874 0.5842)
					(thickness 0.1524)
				)
				(justify mirror)
			)
		)
		(property "Value" ""
			(at 0 0 0)
			(layer "B.Fab")
			(effects
				(font
					(size 1.27 1.27)
				)
				(justify mirror)
			)
		)
		(duplicate_pad_numbers_are_jumpers no)
		(fp_line
			(start 1.651 1.905)
			(end 1.651 -1.905)
			(stroke
				(width 0.1524)
				(type default)
			)
			(layer "B.SilkS")
		)
		(fp_line
			(start 1.651 -1.905)
			(end -1.651 -1.905)
			(stroke
				(width 0.1524)
				(type default)
			)
			(layer "B.SilkS")
		)
		(fp_line
			(start -1.651 1.905)
			(end 1.651 1.905)
			(stroke
				(width 0.1524)
				(type default)
			)
			(layer "B.SilkS")
		)
		(fp_line
			(start -1.651 -1.905)
			(end -1.651 1.905)
			(stroke
				(width 0.1524)
				(type default)
			)
			(layer "B.SilkS")
		)
		(fp_poly
			(pts
				(xy 1.524 0.7112) (xy 1.524 1.7526) (xy 0.508 1.7526) (xy 0.508 0.6985) (xy -0.508 0.6985) (xy -0.508 1.7526)
				(xy -1.524 1.7526) (xy -1.524 0.6985) (xy -1.524 -0.6985) (xy -0.508 -0.6985) (xy -0.508 -1.7526)
				(xy 0.508 -1.7526) (xy 0.508 -0.6985) (xy 1.524 -0.6985) (xy 1.524 0.6985)
			)
			(stroke
				(width 0)
				(type default)
			)
			(fill no)
			(layer "B.CrtYd")
		)
		(fp_text user "G"
			(at -0.432308 2.482596 0)
			(unlocked yes)
			(layer "B.SilkS")
			(effects
				(font
					(size 0.635 0.4064)
					(thickness 0.1524)
				)
				(justify mirror)
			)
		)
		(fp_text user "D"
			(at -1.84277 2.612644 0)
			(unlocked yes)
			(layer "B.SilkS")
			(effects
				(font
					(size 0.635 0.4064)
					(thickness 0.1524)
				)
				(justify mirror)
			)
		)
		(fp_text user "S"
			(at -2.016506 -1.532382 0)
			(unlocked yes)
			(layer "B.SilkS")
			(effects
				(font
					(size 0.635 0.4064)
					(thickness 0.1524)
				)
				(justify mirror)
			)
		)
		(pad "D" smd rect
			(at 0 -1.1176)
			(size 1.016 1.27)
			(layers "B.Cu" "B.Mask" "B.Paste")
			(net "CPLD_UART_RI_P3_N")
		)
		(pad "G" smd rect
			(at 1.016 1.1176)
			(size 1.016 1.27)
			(layers "B.Cu" "B.Mask" "B.Paste")
			(net "TACKOVER_EN")
		)
		(pad "S" smd rect
			(at -1.016 1.1176)
			(size 1.016 1.27)
			(layers "B.Cu" "B.Mask" "B.Paste")
			(net "CPLD_UART_RI_P3_LS_N")
		)
	)
	(footprint ""
		(layer "B.Cu")
		(at 104.408224 -67.228466)
		(property "Reference" "C184"
			(at -4.704842 -1.377188 0)
			(unlocked yes)
			(layer "B.SilkS")
			(effects
				(font
					(size 0.7874 0.5842)
					(thickness 0.1524)
				)
				(justify left mirror)
			)
		)
		(property "Value" ""
			(at 0 0 0)
			(layer "B.Fab")
			(effects
				(font
					(size 1.27 1.27)
				)
				(justify mirror)
			)
		)
		(duplicate_pad_numbers_are_jumpers no)
		(fp_line
			(start -0.7874 -0.4064)
			(end -0.7874 0.4064)
			(stroke
				(width 0.1524)
				(type default)
			)
			(layer "B.SilkS")
		)
		(fp_line
			(start -0.7874 0.4064)
			(end 0.7874 0.4064)
			(stroke
				(width 0.1524)
				(type default)
			)
			(layer "B.SilkS")
		)
		(fp_line
			(start 0 0.381)
			(end 0 -0.381)
			(stroke
				(width 0.1524)
				(type default)
			)
			(layer "B.SilkS")
		)
		(fp_line
			(start 0.7874 -0.4064)
			(end -0.7874 -0.4064)
			(stroke
				(width 0.1524)
				(type default)
			)
			(layer "B.SilkS")
		)
		(fp_line
			(start 0.7874 0.4064)
			(end 0.7874 -0.4064)
			(stroke
				(width 0.1524)
				(type default)
			)
			(layer "B.SilkS")
		)
		(fp_poly
			(pts
				(xy 0.5334 0.254) (xy 0.635 0.254) (xy 0.635 0.2286) (xy 0.635 -0.254) (xy 0.5334 -0.254) (xy 0.5334 -0.2794)
				(xy -0.5334 -0.2794) (xy -0.5334 -0.254) (xy -0.635 -0.254) (xy -0.635 0.254) (xy -0.5334 0.254)
				(xy -0.5334 0.2794) (xy 0.508 0.2794) (xy 0.5334 0.2794)
			)
			(stroke
				(width 0)
				(type default)
			)
			(fill no)
			(layer "B.CrtYd")
		)
		(pad "1" smd rect
			(at -0.40005 0 180)
			(size 0.4572 0.508)
			(layers "B.Cu" "B.Mask" "B.Paste")
			(net "GND")
		)
		(pad "2" smd rect
			(at 0.40005 0 180)
			(size 0.4572 0.508)
			(layers "B.Cu" "B.Mask" "B.Paste")
			(net "XDP_CPU_NODE1_PWROK_STALL_L")
		)
	)
	(footprint ""
		(layer "B.Cu")
		(at 170.820588 -94.36354 -90)
		(property "Reference" "C383"
			(at 2.801112 -2.080006 270)
			(unlocked yes)
			(layer "B.SilkS")
			(effects
				(font
					(size 0.7874 0.5842)
					(thickness 0.1524)
				)
				(justify left mirror)
			)
		)
		(property "Value" ""
			(at 0 0 90)
			(layer "B.Fab")
			(effects
				(font
					(size 1.27 1.27)
				)
				(justify mirror)
			)
		)
		(duplicate_pad_numbers_are_jumpers no)
		(fp_line
			(start -0.7874 0.4064)
			(end 0.7874 0.4064)
			(stroke
				(width 0.1524)
				(type default)
			)
			(layer "B.SilkS")
		)
		(fp_line
			(start 0.7874 0.4064)
			(end 0.7874 -0.4064)
			(stroke
				(width 0.1524)
				(type default)
			)
			(layer "B.SilkS")
		)
		(fp_line
			(start 0 0.381)
			(end 0 -0.381)
			(stroke
				(width 0.1524)
				(type default)
			)
			(layer "B.SilkS")
		)
		(fp_line
			(start -0.7874 -0.4064)
			(end -0.7874 0.4064)
			(stroke
				(width 0.1524)
				(type default)
			)
			(layer "B.SilkS")
		)
		(fp_line
			(start 0.7874 -0.4064)
			(end -0.7874 -0.4064)
			(stroke
				(width 0.1524)
				(type default)
			)
			(layer "B.SilkS")
		)
		(fp_poly
			(pts
				(xy 0.5334 0.254) (xy 0.635 0.254) (xy 0.635 0.2286) (xy 0.635 -0.254) (xy 0.5334 -0.254) (xy 0.5334 -0.2794)
				(xy -0.5334 -0.2794) (xy -0.5334 -0.254) (xy -0.635 -0.254) (xy -0.635 0.254) (xy -0.5334 0.254)
				(xy -0.5334 0.2794) (xy 0.508 0.2794) (xy 0.5334 0.2794)
			)
			(stroke
				(width 0)
				(type default)
			)
			(fill no)
			(layer "B.CrtYd")
		)
		(pad "1" smd rect
			(at -0.40005 0 90)
			(size 0.4572 0.508)
			(layers "B.Cu" "B.Mask" "B.Paste")
			(net "P3V3_USB_NODE1")
		)
		(pad "2" smd rect
			(at 0.40005 0 90)
			(size 0.4572 0.508)
			(layers "B.Cu" "B.Mask" "B.Paste")
			(net "GND")
		)
	)
	(footprint ""
		(layer "B.Cu")
		(at 64.647572 -72.238108 180)
		(property "Reference" "C101"
			(at 12.549632 -31.503366 0)
			(unlocked yes)
			(layer "B.SilkS")
			(effects
				(font
					(size 0.7874 0.5842)
					(thickness 0.1524)
				)
				(justify left mirror)
			)
		)
		(property "Value" ""
			(at 0 0 0)
			(layer "B.Fab")
			(effects
				(font
					(size 1.27 1.27)
				)
				(justify mirror)
			)
		)
		(duplicate_pad_numbers_are_jumpers no)
		(fp_line
			(start 0.7874 0.4064)
			(end 0.7874 -0.4064)
			(stroke
				(width 0.1524)
				(type default)
			)
			(layer "B.SilkS")
		)
		(fp_line
			(start 0.7874 -0.4064)
			(end -0.7874 -0.4064)
			(stroke
				(width 0.1524)
				(type default)
			)
			(layer "B.SilkS")
		)
		(fp_line
			(start 0 0.381)
			(end 0 -0.381)
			(stroke
				(width 0.1524)
				(type default)
			)
			(layer "B.SilkS")
		)
		(fp_line
			(start -0.7874 0.4064)
			(end 0.7874 0.4064)
			(stroke
				(width 0.1524)
				(type default)
			)
			(layer "B.SilkS")
		)
		(fp_line
			(start -0.7874 -0.4064)
			(end -0.7874 0.4064)
			(stroke
				(width 0.1524)
				(type default)
			)
			(layer "B.SilkS")
		)
		(fp_poly
			(pts
				(xy 0.5334 0.254) (xy 0.635 0.254) (xy 0.635 0.2286) (xy 0.635 -0.254) (xy 0.5334 -0.254) (xy 0.5334 -0.2794)
				(xy -0.5334 -0.2794) (xy -0.5334 -0.254) (xy -0.635 -0.254) (xy -0.635 0.254) (xy -0.5334 0.254)
				(xy -0.5334 0.2794) (xy 0.508 0.2794) (xy 0.5334 0.2794)
			)
			(stroke
				(width 0)
				(type default)
			)
			(fill no)
			(layer "B.CrtYd")
		)
		(pad "1" smd rect
			(at -0.40005 0)
			(size 0.4572 0.508)
			(layers "B.Cu" "B.Mask" "B.Paste")
			(net "P1V05_NODE1")
		)
		(pad "2" smd rect
			(at 0.40005 0)
			(size 0.4572 0.508)
			(layers "B.Cu" "B.Mask" "B.Paste")
			(net "GND")
		)
	)
	(footprint ""
		(layer "B.Cu")
		(at 37.929312 -155.118308 180)
		(property "Reference" "C427"
			(at 6.877812 8.942832 0)
			(unlocked yes)
			(layer "B.SilkS")
			(effects
				(font
					(size 0.7874 0.5842)
					(thickness 0.1524)
				)
				(justify left mirror)
			)
		)
		(property "Value" ""
			(at 0 0 0)
			(layer "B.Fab")
			(effects
				(font
					(size 1.27 1.27)
				)
				(justify mirror)
			)
		)
		(duplicate_pad_numbers_are_jumpers no)
		(fp_line
			(start 0.7874 0.4064)
			(end 0.7874 -0.4064)
			(stroke
				(width 0.1524)
				(type default)
			)
			(layer "B.SilkS")
		)
		(fp_line
			(start 0.7874 -0.4064)
			(end -0.7874 -0.4064)
			(stroke
				(width 0.1524)
				(type default)
			)
			(layer "B.SilkS")
		)
		(fp_line
			(start 0 0.381)
			(end 0 -0.381)
			(stroke
				(width 0.1524)
				(type default)
			)
			(layer "B.SilkS")
		)
		(fp_line
			(start -0.7874 0.4064)
			(end 0.7874 0.4064)
			(stroke
				(width 0.1524)
				(type default)
			)
			(layer "B.SilkS")
		)
		(fp_line
			(start -0.7874 -0.4064)
			(end -0.7874 0.4064)
			(stroke
				(width 0.1524)
				(type default)
			)
			(layer "B.SilkS")
		)
		(fp_poly
			(pts
				(xy 0.5334 0.254) (xy 0.635 0.254) (xy 0.635 0.2286) (xy 0.635 -0.254) (xy 0.5334 -0.254) (xy 0.5334 -0.2794)
				(xy -0.5334 -0.2794) (xy -0.5334 -0.254) (xy -0.635 -0.254) (xy -0.635 0.254) (xy -0.5334 0.254)
				(xy -0.5334 0.2794) (xy 0.508 0.2794) (xy 0.5334 0.2794)
			)
			(stroke
				(width 0)
				(type default)
			)
			(fill no)
			(layer "B.CrtYd")
		)
		(pad "1" smd rect
			(at -0.40005 0)
			(size 0.4572 0.508)
			(layers "B.Cu" "B.Mask" "B.Paste")
			(net "P1V9_LAN1")
		)
		(pad "2" smd rect
			(at 0.40005 0)
			(size 0.4572 0.508)
			(layers "B.Cu" "B.Mask" "B.Paste")
			(net "GND")
		)
	)
	(footprint ""
		(layer "B.Cu")
		(at 57.107836 -123.485656 180)
		(property "Reference" "L16"
			(at 41.222676 -53.281326 0)
			(unlocked yes)
			(layer "B.SilkS")
			(effects
				(font
					(size 0.7874 0.5842)
					(thickness 0.1524)
				)
				(justify mirror)
			)
		)
		(property "Value" ""
			(at 0 0 0)
			(layer "B.Fab")
			(effects
				(font
					(size 1.27 1.27)
				)
				(justify mirror)
			)
		)
		(duplicate_pad_numbers_are_jumpers no)
		(fp_line
			(start 1.2954 -0.635)
			(end 1.2954 0.635)
			(stroke
				(width 0.1524)
				(type default)
			)
			(layer "B.SilkS")
		)
		(fp_line
			(start 1.2954 -0.635)
			(end -1.2954 -0.635)
			(stroke
				(width 0.1524)
				(type default)
			)
			(layer "B.SilkS")
		)
		(fp_line
			(start 0.127 -0.5842)
			(end 0.127 0.5842)
			(stroke
				(width 0.1524)
				(type default)
			)
			(layer "B.SilkS")
		)
		(fp_line
			(start -0.127 -0.5842)
			(end -0.127 0.5842)
			(stroke
				(width 0.1524)
				(type default)
			)
			(layer "B.SilkS")
		)
		(fp_line
			(start -1.2954 0.635)
			(end 1.2954 0.635)
			(stroke
				(width 0.1524)
				(type default)
			)
			(layer "B.SilkS")
		)
		(fp_line
			(start -1.2954 -0.635)
			(end -1.2954 0.635)
			(stroke
				(width 0.1524)
				(type default)
			)
			(layer "B.SilkS")
		)
		(fp_poly
			(pts
				(xy 0.9144 0.508) (xy 0.9144 0.3556) (xy 1.143 0.3556) (xy 1.143 -0.3556) (xy 0.9144 -0.3556) (xy 0.9144 -0.508)
				(xy -0.9144 -0.508) (xy -0.9144 -0.3556) (xy -1.143 -0.3556) (xy -1.143 0.3556) (xy -0.9144 0.3556)
				(xy -0.9144 0.508)
			)
			(stroke
				(width 0)
				(type default)
			)
			(fill no)
			(layer "B.CrtYd")
		)
		(pad "1" smd rect
			(at -0.7366 0 270)
			(size 0.7112 0.8128)
			(layers "B.Cu" "B.Mask" "B.Paste")
			(net "BMC_NODE1_HPLLAV33")
		)
		(pad "2" smd rect
			(at 0.7366 0 270)
			(size 0.7112 0.8128)
			(layers "B.Cu" "B.Mask" "B.Paste")
			(net "P3V3_NODE1")
		)
	)
	(footprint ""
		(layer "B.Cu")
		(at 168.462452 -104.87279 90)
		(property "Reference" "C378"
			(at 1.398016 6.049264 270)
			(unlocked yes)
			(layer "B.SilkS")
			(effects
				(font
					(size 0.7874 0.5842)
					(thickness 0.1524)
				)
				(justify left mirror)
			)
		)
		(property "Value" ""
			(at 0 0 90)
			(layer "B.Fab")
			(effects
				(font
					(size 1.27 1.27)
				)
				(justify mirror)
			)
		)
		(duplicate_pad_numbers_are_jumpers no)
		(fp_line
			(start 0.7874 -0.4064)
			(end -0.7874 -0.4064)
			(stroke
				(width 0.1524)
				(type default)
			)
			(layer "B.SilkS")
		)
		(fp_line
			(start -0.7874 -0.4064)
			(end -0.7874 0.4064)
			(stroke
				(width 0.1524)
				(type default)
			)
			(layer "B.SilkS")
		)
		(fp_line
			(start 0 0.381)
			(end 0 -0.381)
			(stroke
				(width 0.1524)
				(type default)
			)
			(layer "B.SilkS")
		)
		(fp_line
			(start 0.7874 0.4064)
			(end 0.7874 -0.4064)
			(stroke
				(width 0.1524)
				(type default)
			)
			(layer "B.SilkS")
		)
		(fp_line
			(start -0.7874 0.4064)
			(end 0.7874 0.4064)
			(stroke
				(width 0.1524)
				(type default)
			)
			(layer "B.SilkS")
		)
		(fp_poly
			(pts
				(xy 0.5334 0.254) (xy 0.635 0.254) (xy 0.635 0.2286) (xy 0.635 -0.254) (xy 0.5334 -0.254) (xy 0.5334 -0.2794)
				(xy -0.5334 -0.2794) (xy -0.5334 -0.254) (xy -0.635 -0.254) (xy -0.635 0.254) (xy -0.5334 0.254)
				(xy -0.5334 0.2794) (xy 0.508 0.2794) (xy 0.5334 0.2794)
			)
			(stroke
				(width 0)
				(type default)
			)
			(fill no)
			(layer "B.CrtYd")
		)
		(pad "1" smd rect
			(at -0.40005 0 270)
			(size 0.4572 0.508)
			(layers "B.Cu" "B.Mask" "B.Paste")
			(net "GND")
		)
		(pad "2" smd rect
			(at 0.40005 0 270)
			(size 0.4572 0.508)
			(layers "B.Cu" "B.Mask" "B.Paste")
			(net "P3V3_NODE1")
		)
	)
)
